(kicad_pcb
	(version 20260206)
	(generator "pcbnew")
	(generator_version "10.0")
	(general
		(thickness 1.6)
		(legacy_teardrops no)
	)
	(paper "A4")
	(title_block
		(title "03242023_DA0F0TMBIJ0_F0T_Motherboard_J_brd_V01_OCP.brd")
		(comment 1 "Grand Teton / footprints 4540-4546 of 6105")
	)
	(layers
		(0 "F.Cu" signal "TOP")
		(4 "In1.Cu" signal "GND")
		(6 "In2.Cu" signal "IN1")
		(8 "In3.Cu" signal "GND1")
		(10 "In4.Cu" signal "IN2")
		(12 "In5.Cu" signal "GND2")
		(14 "In6.Cu" signal "IN3")
		(16 "In7.Cu" signal "GND3")
		(18 "In8.Cu" signal "VCC")
		(20 "In9.Cu" signal "VCC1")
		(22 "In10.Cu" signal "GND4")
		(24 "In11.Cu" signal "IN4")
		(26 "In12.Cu" signal "GND5")
		(28 "In13.Cu" signal "IN5")
		(30 "In14.Cu" signal "GND6")
		(32 "In15.Cu" signal "IN6")
		(34 "In16.Cu" signal "GND7")
		(2 "B.Cu" signal "BOTTOM")
		(9 "F.Adhes" user "F.Adhesive")
		(11 "B.Adhes" user "B.Adhesive")
		(13 "F.Paste" user "Package Geometry/Pastemask Top")
		(15 "B.Paste" user "Package Geometry/Pastemask Bottom")
		(5 "F.SilkS" user "Ref Des/Silkscreen Top")
		(7 "B.SilkS" user "Ref Des/Silkscreen Bottom")
		(1 "F.Mask" user "Board Geometry/Soldermask Top")
		(3 "B.Mask" user "Board Geometry/Soldermask Bottom")
		(17 "Dwgs.User" user "User.Drawings")
		(19 "Cmts.User" user "User.Comments")
		(21 "Eco1.User" user "User.Eco1")
		(23 "Eco2.User" user "User.Eco2")
		(25 "Edge.Cuts" user "Board Geometry/Outline")
		(27 "Margin" user)
		(31 "F.CrtYd" user "Package Geometry/Place Bound Top")
		(29 "B.CrtYd" user "Package Geometry/Place Bound Bottom")
		(35 "F.Fab" user "Ref Des/Assembly Top")
		(33 "B.Fab" user "Ref Des/Assembly Bottom")
	)
	(footprint ""
		(layer "B.Cu")
		(at 200.031858 -194.01917)
		(property "Reference" "R739"
			(at 0 0 0)
			(layer "B.SilkS")
			(hide yes)
			(effects
				(font
					(size 1.27 1.27)
				)
				(justify mirror)
			)
		)
		(property "Value" ""
			(at 0 0 0)
			(layer "B.Fab")
			(effects
				(font
					(size 1.27 1.27)
				)
				(justify mirror)
			)
		)
		(duplicate_pad_numbers_are_jumpers no)
		(fp_line
			(start -0.7874 -0.4064)
			(end -0.7874 0.4064)
			(stroke
				(width 0.1524)
				(type default)
			)
			(layer "B.SilkS")
		)
		(fp_line
			(start -0.7874 0.4064)
			(end 0.7874 0.4064)
			(stroke
				(width 0.1524)
				(type default)
			)
			(layer "B.SilkS")
		)
		(fp_line
			(start 0.7874 -0.4064)
			(end -0.7874 -0.4064)
			(stroke
				(width 0.1524)
				(type default)
			)
			(layer "B.SilkS")
		)
		(fp_line
			(start 0.7874 0.4064)
			(end 0.7874 -0.4064)
			(stroke
				(width 0.1524)
				(type default)
			)
			(layer "B.SilkS")
		)
		(fp_line
			(start -0.67945 -0.3048)
			(end -0.67945 0.3048)
			(stroke
				(width 0.1)
				(type default)
			)
			(layer "B.Fab")
		)
		(fp_line
			(start -0.67945 0.3048)
			(end -0.120396 0.3048)
			(stroke
				(width 0.1)
				(type default)
			)
			(layer "B.Fab")
		)
		(fp_line
			(start -0.12065 -0.3048)
			(end -0.67945 -0.3048)
			(stroke
				(width 0.1)
				(type default)
			)
			(layer "B.Fab")
		)
		(fp_line
			(start -0.12065 -0.2794)
			(end -0.12065 -0.3048)
			(stroke
				(width 0.1)
				(type default)
			)
			(layer "B.Fab")
		)
		(fp_line
			(start -0.120396 0.2794)
			(end 0.12065 0.2794)
			(stroke
				(width 0.1)
				(type default)
			)
			(layer "B.Fab")
		)
		(fp_line
			(start -0.120396 0.3048)
			(end -0.120396 0.2794)
			(stroke
				(width 0.1)
				(type default)
			)
			(layer "B.Fab")
		)
		(fp_line
			(start 0.12065 -0.305054)
			(end 0.12065 -0.2794)
			(stroke
				(width 0.1)
				(type default)
			)
			(layer "B.Fab")
		)
		(fp_line
			(start 0.12065 -0.2794)
			(end -0.12065 -0.2794)
			(stroke
				(width 0.1)
				(type default)
			)
			(layer "B.Fab")
		)
		(fp_line
			(start 0.12065 0.2794)
			(end 0.12065 0.3048)
			(stroke
				(width 0.1)
				(type default)
			)
			(layer "B.Fab")
		)
		(fp_line
			(start 0.12065 0.3048)
			(end 0.67945 0.3048)
			(stroke
				(width 0.1)
				(type default)
			)
			(layer "B.Fab")
		)
		(fp_line
			(start 0.67945 -0.305054)
			(end 0.12065 -0.305054)
			(stroke
				(width 0.1)
				(type default)
			)
			(layer "B.Fab")
		)
		(fp_line
			(start 0.67945 0.3048)
			(end 0.67945 -0.305054)
			(stroke
				(width 0.1)
				(type default)
			)
			(layer "B.Fab")
		)
		(pad "1" smd circle
			(at 0.40005 0 180)
			(size 0 0)
			(layers "B.Cu" "B.Mask" "B.Paste")
			(net "P3V3_AUX")
		)
		(pad "2" smd circle
			(at -0.40005 0 180)
			(size 0 0)
			(layers "B.Cu" "B.Mask" "B.Paste")
			(net "FM_CPU1_SKTOCC_N")
		)
	)
	(footprint ""
		(layer "B.Cu")
		(at 237.842806 -125.400054)
		(property "Reference" "R573"
			(at 0 0 0)
			(layer "B.SilkS")
			(hide yes)
			(effects
				(font
					(size 1.27 1.27)
				)
				(justify mirror)
			)
		)
		(property "Value" ""
			(at 0 0 0)
			(layer "B.Fab")
			(effects
				(font
					(size 1.27 1.27)
				)
				(justify mirror)
			)
		)
		(duplicate_pad_numbers_are_jumpers no)
		(fp_line
			(start -0.7874 -0.4064)
			(end -0.7874 0.4064)
			(stroke
				(width 0.1524)
				(type default)
			)
			(layer "B.SilkS")
		)
		(fp_line
			(start -0.7874 0.4064)
			(end 0.7874 0.4064)
			(stroke
				(width 0.1524)
				(type default)
			)
			(layer "B.SilkS")
		)
		(fp_line
			(start 0.7874 -0.4064)
			(end -0.7874 -0.4064)
			(stroke
				(width 0.1524)
				(type default)
			)
			(layer "B.SilkS")
		)
		(fp_line
			(start 0.7874 0.4064)
			(end 0.7874 -0.4064)
			(stroke
				(width 0.1524)
				(type default)
			)
			(layer "B.SilkS")
		)
		(fp_line
			(start -0.67945 -0.3048)
			(end -0.67945 0.3048)
			(stroke
				(width 0.1)
				(type default)
			)
			(layer "B.Fab")
		)
		(fp_line
			(start -0.67945 0.3048)
			(end -0.120396 0.3048)
			(stroke
				(width 0.1)
				(type default)
			)
			(layer "B.Fab")
		)
		(fp_line
			(start -0.12065 -0.3048)
			(end -0.67945 -0.3048)
			(stroke
				(width 0.1)
				(type default)
			)
			(layer "B.Fab")
		)
		(fp_line
			(start -0.12065 -0.2794)
			(end -0.12065 -0.3048)
			(stroke
				(width 0.1)
				(type default)
			)
			(layer "B.Fab")
		)
		(fp_line
			(start -0.120396 0.2794)
			(end 0.12065 0.2794)
			(stroke
				(width 0.1)
				(type default)
			)
			(layer "B.Fab")
		)
		(fp_line
			(start -0.120396 0.3048)
			(end -0.120396 0.2794)
			(stroke
				(width 0.1)
				(type default)
			)
			(layer "B.Fab")
		)
		(fp_line
			(start 0.12065 -0.305054)
			(end 0.12065 -0.2794)
			(stroke
				(width 0.1)
				(type default)
			)
			(layer "B.Fab")
		)
		(fp_line
			(start 0.12065 -0.2794)
			(end -0.12065 -0.2794)
			(stroke
				(width 0.1)
				(type default)
			)
			(layer "B.Fab")
		)
		(fp_line
			(start 0.12065 0.2794)
			(end 0.12065 0.3048)
			(stroke
				(width 0.1)
				(type default)
			)
			(layer "B.Fab")
		)
		(fp_line
			(start 0.12065 0.3048)
			(end 0.67945 0.3048)
			(stroke
				(width 0.1)
				(type default)
			)
			(layer "B.Fab")
		)
		(fp_line
			(start 0.67945 -0.305054)
			(end 0.12065 -0.305054)
			(stroke
				(width 0.1)
				(type default)
			)
			(layer "B.Fab")
		)
		(fp_line
			(start 0.67945 0.3048)
			(end 0.67945 -0.305054)
			(stroke
				(width 0.1)
				(type default)
			)
			(layer "B.Fab")
		)
		(pad "1" smd circle
			(at 0.40005 0 180)
			(size 0 0)
			(layers "B.Cu" "B.Mask" "B.Paste")
			(net "P3V3")
		)
		(pad "2" smd circle
			(at -0.40005 0 180)
			(size 0 0)
			(layers "B.Cu" "B.Mask" "B.Paste")
			(net "FM_DB2000_VSBEN")
		)
	)
	(footprint ""
		(layer "B.Cu")
		(at 164.64788 -118.836948)
		(property "Reference" "R1410"
			(at 0 0 0)
			(layer "B.SilkS")
			(hide yes)
			(effects
				(font
					(size 1.27 1.27)
				)
				(justify mirror)
			)
		)
		(property "Value" ""
			(at 0 0 0)
			(layer "B.Fab")
			(effects
				(font
					(size 1.27 1.27)
				)
				(justify mirror)
			)
		)
		(duplicate_pad_numbers_are_jumpers no)
		(fp_line
			(start -0.7874 -0.4064)
			(end -0.7874 0.4064)
			(stroke
				(width 0.1524)
				(type default)
			)
			(layer "B.SilkS")
		)
		(fp_line
			(start -0.7874 0.4064)
			(end 0.7874 0.4064)
			(stroke
				(width 0.1524)
				(type default)
			)
			(layer "B.SilkS")
		)
		(fp_line
			(start 0.7874 -0.4064)
			(end -0.7874 -0.4064)
			(stroke
				(width 0.1524)
				(type default)
			)
			(layer "B.SilkS")
		)
		(fp_line
			(start 0.7874 0.4064)
			(end 0.7874 -0.4064)
			(stroke
				(width 0.1524)
				(type default)
			)
			(layer "B.SilkS")
		)
		(fp_line
			(start -0.67945 -0.3048)
			(end -0.67945 0.3048)
			(stroke
				(width 0.1)
				(type default)
			)
			(layer "B.Fab")
		)
		(fp_line
			(start -0.67945 0.3048)
			(end -0.120396 0.3048)
			(stroke
				(width 0.1)
				(type default)
			)
			(layer "B.Fab")
		)
		(fp_line
			(start -0.12065 -0.3048)
			(end -0.67945 -0.3048)
			(stroke
				(width 0.1)
				(type default)
			)
			(layer "B.Fab")
		)
		(fp_line
			(start -0.12065 -0.2794)
			(end -0.12065 -0.3048)
			(stroke
				(width 0.1)
				(type default)
			)
			(layer "B.Fab")
		)
		(fp_line
			(start -0.120396 0.2794)
			(end 0.12065 0.2794)
			(stroke
				(width 0.1)
				(type default)
			)
			(layer "B.Fab")
		)
		(fp_line
			(start -0.120396 0.3048)
			(end -0.120396 0.2794)
			(stroke
				(width 0.1)
				(type default)
			)
			(layer "B.Fab")
		)
		(fp_line
			(start 0.12065 -0.305054)
			(end 0.12065 -0.2794)
			(stroke
				(width 0.1)
				(type default)
			)
			(layer "B.Fab")
		)
		(fp_line
			(start 0.12065 -0.2794)
			(end -0.12065 -0.2794)
			(stroke
				(width 0.1)
				(type default)
			)
			(layer "B.Fab")
		)
		(fp_line
			(start 0.12065 0.2794)
			(end 0.12065 0.3048)
			(stroke
				(width 0.1)
				(type default)
			)
			(layer "B.Fab")
		)
		(fp_line
			(start 0.12065 0.3048)
			(end 0.67945 0.3048)
			(stroke
				(width 0.1)
				(type default)
			)
			(layer "B.Fab")
		)
		(fp_line
			(start 0.67945 -0.305054)
			(end 0.12065 -0.305054)
			(stroke
				(width 0.1)
				(type default)
			)
			(layer "B.Fab")
		)
		(fp_line
			(start 0.67945 0.3048)
			(end 0.67945 -0.305054)
			(stroke
				(width 0.1)
				(type default)
			)
			(layer "B.Fab")
		)
		(pad "1" smd circle
			(at 0.40005 0 180)
			(size 0 0)
			(layers "B.Cu" "B.Mask" "B.Paste")
			(net "FM_PVCCFA_EHV_CPU1_R_EN")
		)
		(pad "2" smd circle
			(at -0.40005 0 180)
			(size 0 0)
			(layers "B.Cu" "B.Mask" "B.Paste")
			(net "GND")
		)
	)
	(footprint ""
		(layer "B.Cu")
		(at 334.02016 -386.8928)
		(property "Reference" "ME11"
			(at 9.652 -9.540748 0)
			(unlocked yes)
			(layer "B.SilkS")
			(effects
				(font
					(size 0.7874 0.5842)
					(thickness 0.1524)
				)
				(justify left mirror)
			)
		)
		(property "Value" ""
			(at 0 0 0)
			(layer "B.Fab")
			(effects
				(font
					(size 1.27 1.27)
				)
				(justify mirror)
			)
		)
		(duplicate_pad_numbers_are_jumpers no)
		(zone
			(layer "B.Cu")
			(hatch none 0.5)
			(connect_pads
				(clearance 0)
			)
			(min_thickness 0.25)
			(keepout
				(tracks allowed)
				(vias allowed)
				(pads allowed)
				(copperpour allowed)
				(footprints not_allowed)
			)
			(placement
				(enabled no)
				(sheetname "")
			)
			(fill
				(thermal_gap 0.5)
				(thermal_bridge_width 0.5)
				(island_removal_mode 0)
			)
			(polygon
				(pts
					(arc
						(start 344.02014 -386.8928)
						(mid 324.02018 -386.8928)
						(end 344.02014 -386.8928)
					)
				)
			)
		)
	)
	(footprint ""
		(layer "B.Cu")
		(at 179.352448 -404.287482)
		(property "Reference" "PR2149"
			(at 0 0 0)
			(layer "B.SilkS")
			(hide yes)
			(effects
				(font
					(size 1.27 1.27)
				)
				(justify mirror)
			)
		)
		(property "Value" ""
			(at 0 0 0)
			(layer "B.Fab")
			(effects
				(font
					(size 1.27 1.27)
				)
				(justify mirror)
			)
		)
		(duplicate_pad_numbers_are_jumpers no)
		(fp_line
			(start -0.7874 -0.4064)
			(end -0.7874 0.4064)
			(stroke
				(width 0.1524)
				(type default)
			)
			(layer "B.SilkS")
		)
		(fp_line
			(start -0.7874 0.4064)
			(end 0.7874 0.4064)
			(stroke
				(width 0.1524)
				(type default)
			)
			(layer "B.SilkS")
		)
		(fp_line
			(start 0.7874 -0.4064)
			(end -0.7874 -0.4064)
			(stroke
				(width 0.1524)
				(type default)
			)
			(layer "B.SilkS")
		)
		(fp_line
			(start 0.7874 0.4064)
			(end 0.7874 -0.4064)
			(stroke
				(width 0.1524)
				(type default)
			)
			(layer "B.SilkS")
		)
		(fp_line
			(start -0.67945 -0.3048)
			(end -0.67945 0.3048)
			(stroke
				(width 0.1)
				(type default)
			)
			(layer "B.Fab")
		)
		(fp_line
			(start -0.67945 0.3048)
			(end -0.120396 0.3048)
			(stroke
				(width 0.1)
				(type default)
			)
			(layer "B.Fab")
		)
		(fp_line
			(start -0.12065 -0.3048)
			(end -0.67945 -0.3048)
			(stroke
				(width 0.1)
				(type default)
			)
			(layer "B.Fab")
		)
		(fp_line
			(start -0.12065 -0.2794)
			(end -0.12065 -0.3048)
			(stroke
				(width 0.1)
				(type default)
			)
			(layer "B.Fab")
		)
		(fp_line
			(start -0.120396 0.2794)
			(end 0.12065 0.2794)
			(stroke
				(width 0.1)
				(type default)
			)
			(layer "B.Fab")
		)
		(fp_line
			(start -0.120396 0.3048)
			(end -0.120396 0.2794)
			(stroke
				(width 0.1)
				(type default)
			)
			(layer "B.Fab")
		)
		(fp_line
			(start 0.12065 -0.305054)
			(end 0.12065 -0.2794)
			(stroke
				(width 0.1)
				(type default)
			)
			(layer "B.Fab")
		)
		(fp_line
			(start 0.12065 -0.2794)
			(end -0.12065 -0.2794)
			(stroke
				(width 0.1)
				(type default)
			)
			(layer "B.Fab")
		)
		(fp_line
			(start 0.12065 0.2794)
			(end 0.12065 0.3048)
			(stroke
				(width 0.1)
				(type default)
			)
			(layer "B.Fab")
		)
		(fp_line
			(start 0.12065 0.3048)
			(end 0.67945 0.3048)
			(stroke
				(width 0.1)
				(type default)
			)
			(layer "B.Fab")
		)
		(fp_line
			(start 0.67945 -0.305054)
			(end 0.12065 -0.305054)
			(stroke
				(width 0.1)
				(type default)
			)
			(layer "B.Fab")
		)
		(fp_line
			(start 0.67945 0.3048)
			(end 0.67945 -0.305054)
			(stroke
				(width 0.1)
				(type default)
			)
			(layer "B.Fab")
		)
		(pad "1" smd circle
			(at 0.40005 0 180)
			(size 0 0)
			(layers "B.Cu" "B.Mask" "B.Paste")
			(net "HSC_VDD_R")
		)
		(pad "2" smd circle
			(at -0.40005 0 180)
			(size 0 0)
			(layers "B.Cu" "B.Mask" "B.Paste")
			(net "HSC_VDD")
		)
	)
	(footprint ""
		(layer "B.Cu")
		(at 456.003406 -318.266826 180)
		(property "Reference" "R2493"
			(at 0 0 0)
			(layer "B.SilkS")
			(hide yes)
			(effects
				(font
					(size 1.27 1.27)
				)
				(justify mirror)
			)
		)
		(property "Value" ""
			(at 0 0 0)
			(layer "B.Fab")
			(effects
				(font
					(size 1.27 1.27)
				)
				(justify mirror)
			)
		)
		(duplicate_pad_numbers_are_jumpers no)
		(fp_line
			(start 0.7874 0.4064)
			(end 0.7874 -0.4064)
			(stroke
				(width 0.1524)
				(type default)
			)
			(layer "B.SilkS")
		)
		(fp_line
			(start 0.7874 -0.4064)
			(end -0.7874 -0.4064)
			(stroke
				(width 0.1524)
				(type default)
			)
			(layer "B.SilkS")
		)
		(fp_line
			(start -0.7874 0.4064)
			(end 0.7874 0.4064)
			(stroke
				(width 0.1524)
				(type default)
			)
			(layer "B.SilkS")
		)
		(fp_line
			(start -0.7874 -0.4064)
			(end -0.7874 0.4064)
			(stroke
				(width 0.1524)
				(type default)
			)
			(layer "B.SilkS")
		)
		(fp_line
			(start 0.67945 0.3048)
			(end 0.67945 -0.305054)
			(stroke
				(width 0.1)
				(type default)
			)
			(layer "B.Fab")
		)
		(fp_line
			(start 0.67945 -0.305054)
			(end 0.12065 -0.305054)
			(stroke
				(width 0.1)
				(type default)
			)
			(layer "B.Fab")
		)
		(fp_line
			(start 0.12065 0.3048)
			(end 0.67945 0.3048)
			(stroke
				(width 0.1)
				(type default)
			)
			(layer "B.Fab")
		)
		(fp_line
			(start 0.12065 0.2794)
			(end 0.12065 0.3048)
			(stroke
				(width 0.1)
				(type default)
			)
			(layer "B.Fab")
		)
		(fp_line
			(start 0.12065 -0.2794)
			(end -0.12065 -0.2794)
			(stroke
				(width 0.1)
				(type default)
			)
			(layer "B.Fab")
		)
		(fp_line
			(start 0.12065 -0.305054)
			(end 0.12065 -0.2794)
			(stroke
				(width 0.1)
				(type default)
			)
			(layer "B.Fab")
		)
		(fp_line
			(start -0.120396 0.3048)
			(end -0.120396 0.2794)
			(stroke
				(width 0.1)
				(type default)
			)
			(layer "B.Fab")
		)
		(fp_line
			(start -0.120396 0.2794)
			(end 0.12065 0.2794)
			(stroke
				(width 0.1)
				(type default)
			)
			(layer "B.Fab")
		)
		(fp_line
			(start -0.12065 -0.2794)
			(end -0.12065 -0.3048)
			(stroke
				(width 0.1)
				(type default)
			)
			(layer "B.Fab")
		)
		(fp_line
			(start -0.12065 -0.3048)
			(end -0.67945 -0.3048)
			(stroke
				(width 0.1)
				(type default)
			)
			(layer "B.Fab")
		)
		(fp_line
			(start -0.67945 0.3048)
			(end -0.120396 0.3048)
			(stroke
				(width 0.1)
				(type default)
			)
			(layer "B.Fab")
		)
		(fp_line
			(start -0.67945 -0.3048)
			(end -0.67945 0.3048)
			(stroke
				(width 0.1)
				(type default)
			)
			(layer "B.Fab")
		)
		(pad "1" smd circle
			(at 0.40005 0)
			(size 0 0)
			(layers "B.Cu" "B.Mask" "B.Paste")
			(net "PWRGD_FAIL_CPU0_GH")
		)
		(pad "2" smd circle
			(at -0.40005 0)
			(size 0 0)
			(layers "B.Cu" "B.Mask" "B.Paste")
			(net "PWRGD_FAIL_CPU0_GH_R1")
		)
	)
	(footprint ""
		(layer "B.Cu")
		(at 283.430726 -193.691256 -90)
		(property "Reference" "C622"
			(at 0 0 90)
			(layer "B.SilkS")
			(hide yes)
			(effects
				(font
					(size 1.27 1.27)
				)
				(justify mirror)
			)
		)
		(property "Value" ""
			(at 0 0 90)
			(layer "B.Fab")
			(effects
				(font
					(size 1.27 1.27)
				)
				(justify mirror)
			)
		)
		(duplicate_pad_numbers_are_jumpers no)
		(fp_line
			(start -0.7874 0.4064)
			(end 0.7874 0.4064)
			(stroke
				(width 0.1524)
				(type default)
			)
			(layer "B.SilkS")
		)
		(fp_line
			(start 0.7874 0.4064)
			(end 0.7874 -0.4064)
			(stroke
				(width 0.1524)
				(type default)
			)
			(layer "B.SilkS")
		)
		(fp_line
			(start -0.7874 -0.4064)
			(end -0.7874 0.4064)
			(stroke
				(width 0.1524)
				(type default)
			)
			(layer "B.SilkS")
		)
		(fp_line
			(start 0.7874 -0.4064)
			(end -0.7874 -0.4064)
			(stroke
				(width 0.1524)
				(type default)
			)
			(layer "B.SilkS")
		)
		(fp_line
			(start -0.67945 0.3048)
			(end -0.120396 0.3048)
			(stroke
				(width 0.1)
				(type default)
			)
			(layer "B.Fab")
		)
		(fp_line
			(start -0.120396 0.3048)
			(end -0.120396 0.2794)
			(stroke
				(width 0.1)
				(type default)
			)
			(layer "B.Fab")
		)
		(fp_line
			(start 0.12065 0.3048)
			(end 0.67945 0.3048)
			(stroke
				(width 0.1)
				(type default)
			)
			(layer "B.Fab")
		)
		(fp_line
			(start 0.67945 0.3048)
			(end 0.67945 -0.305054)
			(stroke
				(width 0.1)
				(type default)
			)
			(layer "B.Fab")
		)
		(fp_line
			(start -0.120396 0.2794)
			(end 0.12065 0.2794)
			(stroke
				(width 0.1)
				(type default)
			)
			(layer "B.Fab")
		)
		(fp_line
			(start 0.12065 0.2794)
			(end 0.12065 0.3048)
			(stroke
				(width 0.1)
				(type default)
			)
			(layer "B.Fab")
		)
		(fp_line
			(start -0.12065 -0.2794)
			(end -0.12065 -0.3048)
			(stroke
				(width 0.1)
				(type default)
			)
			(layer "B.Fab")
		)
		(fp_line
			(start 0.12065 -0.2794)
			(end -0.12065 -0.2794)
			(stroke
				(width 0.1)
				(type default)
			)
			(layer "B.Fab")
		)
		(fp_line
			(start -0.67945 -0.3048)
			(end -0.67945 0.3048)
			(stroke
				(width 0.1)
				(type default)
			)
			(layer "B.Fab")
		)
		(fp_line
			(start -0.12065 -0.3048)
			(end -0.67945 -0.3048)
			(stroke
				(width 0.1)
				(type default)
			)
			(layer "B.Fab")
		)
		(fp_line
			(start 0.12065 -0.305054)
			(end 0.12065 -0.2794)
			(stroke
				(width 0.1)
				(type default)
			)
			(layer "B.Fab")
		)
		(fp_line
			(start 0.67945 -0.305054)
			(end 0.12065 -0.305054)
			(stroke
				(width 0.1)
				(type default)
			)
			(layer "B.Fab")
		)
		(pad "1" smd circle
			(at 0.40005 0 90)
			(size 0 0)
			(layers "B.Cu" "B.Mask" "B.Paste")
			(net "RST_PLD_CPU0_DRAM_AB_N")
		)
		(pad "2" smd circle
			(at -0.40005 0 90)
			(size 0 0)
			(layers "B.Cu" "B.Mask" "B.Paste")
			(net "GND")
		)
	)
)
